# S9S_MB_2U (Grand Teton) — schematic netlist excerpt (pin names and nets, part order shuffled) for the footprints in the layout excerpt that follows; sources: Cadence DE-HDL packaged netlist, KiCad conversion of 03242023_DA0F0TMBIJ0_F0T_Motherboard_J_brd_V01_OCP.brd

R4602  Q_RES  0 5% CHIP  pkg 0402LF  page 161 : A = CLK_50M_NCSI_OCP_V3_2_ISO ; B = CLK_50M_NCSI_OCP_V3_2_ISO_R
PC724_P1_1  Q_CAP  22UF 16V 20% X6S  pkg C0805  page 289 : A = SW_P12V_PVCCFA_EHV_FIVRA_CPU1_R ; B = GND
R3514  Q_RES  54.9K 1% CHIP  pkg 0402LF  page 148 : A = P3V3_AUX ; B = FM_SMB_2_ALERT_GPU_N

(kicad_pcb
	(version 20260206)
	(generator "pcbnew")
	(generator_version "10.0")
	(general
		(thickness 1.6)
		(legacy_teardrops no)
	)
	(paper "A4")
	(title_block
		(title "03242023_DA0F0TMBIJ0_F0T_Motherboard_J_brd_V01_OCP.brd")
		(comment 1 "Grand Teton / footprints 4146-4148 of 6105")
	)
	(layers
		(0 "F.Cu" signal "TOP")
		(4 "In1.Cu" signal "GND")
		(6 "In2.Cu" signal "IN1")
		(8 "In3.Cu" signal "GND1")
		(10 "In4.Cu" signal "IN2")
		(12 "In5.Cu" signal "GND2")
		(14 "In6.Cu" signal "IN3")
		(16 "In7.Cu" signal "GND3")
		(18 "In8.Cu" signal "VCC")
		(20 "In9.Cu" signal "VCC1")
		(22 "In10.Cu" signal "GND4")
		(24 "In11.Cu" signal "IN4")
		(26 "In12.Cu" signal "GND5")
		(28 "In13.Cu" signal "IN5")
		(30 "In14.Cu" signal "GND6")
		(32 "In15.Cu" signal "IN6")
		(34 "In16.Cu" signal "GND7")
		(2 "B.Cu" signal "BOTTOM")
		(9 "F.Adhes" user "F.Adhesive")
		(11 "B.Adhes" user "B.Adhesive")
		(13 "F.Paste" user "Package Geometry/Pastemask Top")
		(15 "B.Paste" user "Package Geometry/Pastemask Bottom")
		(5 "F.SilkS" user "Ref Des/Silkscreen Top")
		(7 "B.SilkS" user "Ref Des/Silkscreen Bottom")
		(1 "F.Mask" user "Board Geometry/Soldermask Top")
		(3 "B.Mask" user "Board Geometry/Soldermask Bottom")
		(17 "Dwgs.User" user "User.Drawings")
		(19 "Cmts.User" user "User.Comments")
		(21 "Eco1.User" user "User.Eco1")
		(23 "Eco2.User" user "User.Eco2")
		(25 "Edge.Cuts" user "Board Geometry/Outline")
		(27 "Margin" user)
		(31 "F.CrtYd" user "Package Geometry/Place Bound Top")
		(29 "B.CrtYd" user "Package Geometry/Place Bound Bottom")
		(35 "F.Fab" user "Ref Des/Assembly Top")
		(33 "B.Fab" user "Ref Des/Assembly Bottom")
	)
	(footprint ""
		(layer "F.Cu")
		(at 86.311994 -31.667958 90)
		(property "Reference" "R4602"
			(at 0 0 90)
			(layer "F.SilkS")
			(hide yes)
			(effects
				(font
					(size 1.27 1.27)
				)
			)
		)
		(property "Value" ""
			(at 0 0 90)
			(layer "F.Fab")
			(effects
				(font
					(size 1.27 1.27)
				)
			)
		)
		(duplicate_pad_numbers_are_jumpers no)
		(fp_line
			(start 0.7874 -0.4064)
			(end 0.7874 0.4064)
			(stroke
				(width 0.1524)
				(type default)
			)
			(layer "F.SilkS")
		)
		(fp_line
			(start -0.7874 -0.4064)
			(end 0.7874 -0.4064)
			(stroke
				(width 0.1524)
				(type default)
			)
			(layer "F.SilkS")
		)
		(fp_line
			(start 0.7874 0.4064)
			(end -0.7874 0.4064)
			(stroke
				(width 0.1524)
				(type default)
			)
			(layer "F.SilkS")
		)
		(fp_line
			(start -0.7874 0.4064)
			(end -0.7874 -0.4064)
			(stroke
				(width 0.1524)
				(type default)
			)
			(layer "F.SilkS")
		)
		(fp_line
			(start -0.12065 -0.305054)
			(end -0.12065 -0.2794)
			(stroke
				(width 0.1)
				(type default)
			)
			(layer "F.Fab")
		)
		(fp_line
			(start -0.67945 -0.305054)
			(end -0.12065 -0.305054)
			(stroke
				(width 0.1)
				(type default)
			)
			(layer "F.Fab")
		)
		(fp_line
			(start 0.67945 -0.3048)
			(end 0.67945 0.3048)
			(stroke
				(width 0.1)
				(type default)
			)
			(layer "F.Fab")
		)
		(fp_line
			(start 0.12065 -0.3048)
			(end 0.67945 -0.3048)
			(stroke
				(width 0.1)
				(type default)
			)
			(layer "F.Fab")
		)
		(fp_line
			(start 0.12065 -0.2794)
			(end 0.12065 -0.3048)
			(stroke
				(width 0.1)
				(type default)
			)
			(layer "F.Fab")
		)
		(fp_line
			(start -0.12065 -0.2794)
			(end 0.12065 -0.2794)
			(stroke
				(width 0.1)
				(type default)
			)
			(layer "F.Fab")
		)
		(fp_line
			(start 0.120396 0.2794)
			(end -0.12065 0.2794)
			(stroke
				(width 0.1)
				(type default)
			)
			(layer "F.Fab")
		)
		(fp_line
			(start -0.12065 0.2794)
			(end -0.12065 0.3048)
			(stroke
				(width 0.1)
				(type default)
			)
			(layer "F.Fab")
		)
		(fp_line
			(start 0.67945 0.3048)
			(end 0.120396 0.3048)
			(stroke
				(width 0.1)
				(type default)
			)
			(layer "F.Fab")
		)
		(fp_line
			(start 0.120396 0.3048)
			(end 0.120396 0.2794)
			(stroke
				(width 0.1)
				(type default)
			)
			(layer "F.Fab")
		)
		(fp_line
			(start -0.12065 0.3048)
			(end -0.67945 0.3048)
			(stroke
				(width 0.1)
				(type default)
			)
			(layer "F.Fab")
		)
		(fp_line
			(start -0.67945 0.3048)
			(end -0.67945 -0.305054)
			(stroke
				(width 0.1)
				(type default)
			)
			(layer "F.Fab")
		)
		(pad "1" smd circle
			(at -0.40005 0 90)
			(size 0 0)
			(layers "F.Cu" "F.Mask" "F.Paste")
			(net "CLK_50M_NCSI_OCP_V3_2_ISO")
		)
		(pad "2" smd circle
			(at 0.40005 0 90)
			(size 0 0)
			(layers "F.Cu" "F.Mask" "F.Paste")
			(net "CLK_50M_NCSI_OCP_V3_2_ISO_R")
		)
	)
	(footprint ""
		(layer "F.Cu")
		(at 113.28908 -397.874998 -90)
		(property "Reference" "R3514"
			(at 0 0 270)
			(layer "F.SilkS")
			(hide yes)
			(effects
				(font
					(size 1.27 1.27)
				)
			)
		)
		(property "Value" ""
			(at 0 0 270)
			(layer "F.Fab")
			(effects
				(font
					(size 1.27 1.27)
				)
			)
		)
		(duplicate_pad_numbers_are_jumpers no)
		(fp_line
			(start -0.7874 0.4064)
			(end -0.7874 -0.4064)
			(stroke
				(width 0.1524)
				(type default)
			)
			(layer "F.SilkS")
		)
		(fp_line
			(start 0.7874 0.4064)
			(end -0.7874 0.4064)
			(stroke
				(width 0.1524)
				(type default)
			)
			(layer "F.SilkS")
		)
		(fp_line
			(start -0.7874 -0.4064)
			(end 0.7874 -0.4064)
			(stroke
				(width 0.1524)
				(type default)
			)
			(layer "F.SilkS")
		)
		(fp_line
			(start 0.7874 -0.4064)
			(end 0.7874 0.4064)
			(stroke
				(width 0.1524)
				(type default)
			)
			(layer "F.SilkS")
		)
		(fp_line
			(start -0.67945 0.3048)
			(end -0.67945 -0.305054)
			(stroke
				(width 0.1)
				(type default)
			)
			(layer "F.Fab")
		)
		(fp_line
			(start -0.12065 0.3048)
			(end -0.67945 0.3048)
			(stroke
				(width 0.1)
				(type default)
			)
			(layer "F.Fab")
		)
		(fp_line
			(start 0.120396 0.3048)
			(end 0.120396 0.2794)
			(stroke
				(width 0.1)
				(type default)
			)
			(layer "F.Fab")
		)
		(fp_line
			(start 0.67945 0.3048)
			(end 0.120396 0.3048)
			(stroke
				(width 0.1)
				(type default)
			)
			(layer "F.Fab")
		)
		(fp_line
			(start -0.12065 0.2794)
			(end -0.12065 0.3048)
			(stroke
				(width 0.1)
				(type default)
			)
			(layer "F.Fab")
		)
		(fp_line
			(start 0.120396 0.2794)
			(end -0.12065 0.2794)
			(stroke
				(width 0.1)
				(type default)
			)
			(layer "F.Fab")
		)
		(fp_line
			(start -0.12065 -0.2794)
			(end 0.12065 -0.2794)
			(stroke
				(width 0.1)
				(type default)
			)
			(layer "F.Fab")
		)
		(fp_line
			(start 0.12065 -0.2794)
			(end 0.12065 -0.3048)
			(stroke
				(width 0.1)
				(type default)
			)
			(layer "F.Fab")
		)
		(fp_line
			(start 0.12065 -0.3048)
			(end 0.67945 -0.3048)
			(stroke
				(width 0.1)
				(type default)
			)
			(layer "F.Fab")
		)
		(fp_line
			(start 0.67945 -0.3048)
			(end 0.67945 0.3048)
			(stroke
				(width 0.1)
				(type default)
			)
			(layer "F.Fab")
		)
		(fp_line
			(start -0.67945 -0.305054)
			(end -0.12065 -0.305054)
			(stroke
				(width 0.1)
				(type default)
			)
			(layer "F.Fab")
		)
		(fp_line
			(start -0.12065 -0.305054)
			(end -0.12065 -0.2794)
			(stroke
				(width 0.1)
				(type default)
			)
			(layer "F.Fab")
		)
		(pad "1" smd circle
			(at -0.40005 0 270)
			(size 0 0)
			(layers "F.Cu" "F.Mask" "F.Paste")
			(net "P3V3_AUX")
		)
		(pad "2" smd circle
			(at 0.40005 0 270)
			(size 0 0)
			(layers "F.Cu" "F.Mask" "F.Paste")
			(net "FM_SMB_2_ALERT_GPU_N")
		)
	)
	(footprint ""
		(layer "F.Cu")
		(at 176.317148 -358.12476)
		(property "Reference" "PC724_P1_1"
			(at 0 0 0)
			(layer "F.SilkS")
			(hide yes)
			(effects
				(font
					(size 1.27 1.27)
				)
			)
		)
		(property "Value" ""
			(at 0 0 0)
			(layer "F.Fab")
			(effects
				(font
					(size 1.27 1.27)
				)
			)
		)
		(duplicate_pad_numbers_are_jumpers no)
		(fp_line
			(start -1.524 -0.762)
			(end 1.524 -0.762)
			(stroke
				(width 0.1524)
				(type default)
			)
			(layer "F.SilkS")
		)
		(fp_line
			(start -1.524 0.762)
			(end -1.524 -0.762)
			(stroke
				(width 0.1524)
				(type default)
			)
			(layer "F.SilkS")
		)
		(fp_line
			(start 1.524 -0.762)
			(end 1.524 0.762)
			(stroke
				(width 0.1524)
				(type default)
			)
			(layer "F.SilkS")
		)
		(fp_line
			(start 1.524 0.762)
			(end -1.524 0.762)
			(stroke
				(width 0.1524)
				(type default)
			)
			(layer "F.SilkS")
		)
		(fp_line
			(start -1.1049 -0.724916)
			(end -1.1049 0.724916)
			(stroke
				(width 0.1)
				(type default)
			)
			(layer "F.Fab")
		)
		(fp_line
			(start -1.1049 0.724916)
			(end 1.1049 0.724916)
			(stroke
				(width 0.1)
				(type default)
			)
			(layer "F.Fab")
		)
		(fp_line
			(start 1.1049 -0.724916)
			(end -1.1049 -0.724916)
			(stroke
				(width 0.1)
				(type default)
			)
			(layer "F.Fab")
		)
		(fp_line
			(start 1.1049 0.724916)
			(end 1.1049 -0.724916)
			(stroke
				(width 0.1)
				(type default)
			)
			(layer "F.Fab")
		)
		(pad "1" smd rect
			(at -0.889 0 180)
			(size 1.016 1.27)
			(layers "F.Cu" "F.Mask" "F.Paste")
			(net "SW_P12V_PVCCFA_EHV_FIVRA_CPU1_R")
		)
		(pad "2" smd rect
			(at 0.889 0 180)
			(size 1.016 1.27)
			(layers "F.Cu" "F.Mask" "F.Paste")
			(net "GND")
		)
	)
)
